(kicad_pcb
	(version 20260206)
	(generator "pcbnew")
	(generator_version "10.0")
	(general
		(thickness 1.6)
		(legacy_teardrops no)
	)
	(paper "A4")
	(title_block
		(title "Wiwynn_Tioga_Pass_MB.brd")
		(comment 1 "Tioga Pass / footprints 4074-4080 of 4770")
	)
	(layers
		(0 "F.Cu" signal "TOP")
		(4 "In1.Cu" signal "L2GND")
		(6 "In2.Cu" signal "L3")
		(8 "In3.Cu" signal "L4GND")
		(10 "In4.Cu" signal "L5")
		(12 "In5.Cu" signal "L6GND")
		(14 "In6.Cu" signal "L7VCC")
		(16 "In7.Cu" signal "L8VCC")
		(18 "In8.Cu" signal "L9GND")
		(20 "In9.Cu" signal "L10")
		(22 "In10.Cu" signal "L11GND")
		(24 "In11.Cu" signal "L12")
		(26 "In12.Cu" signal "L13GND")
		(2 "B.Cu" signal "BOTTOM")
		(9 "F.Adhes" user "F.Adhesive")
		(11 "B.Adhes" user "B.Adhesive")
		(13 "F.Paste" user "Package Geometry/Pastemask Top")
		(15 "B.Paste" user "Package Geometry/Pastemask Bottom")
		(5 "F.SilkS" user "Ref Des/Silkscreen Top")
		(7 "B.SilkS" user "Ref Des/Silkscreen Bottom")
		(1 "F.Mask" user "Board Geometry/Soldermask Top")
		(3 "B.Mask" user "Board Geometry/Soldermask Bottom")
		(17 "Dwgs.User" user "User.Drawings")
		(19 "Cmts.User" user "User.Comments")
		(21 "Eco1.User" user "User.Eco1")
		(23 "Eco2.User" user "User.Eco2")
		(25 "Edge.Cuts" user "Board Geometry/Outline")
		(27 "Margin" user)
		(31 "F.CrtYd" user "Package Geometry/Place Bound Top")
		(29 "B.CrtYd" user "Package Geometry/Place Bound Bottom")
		(35 "F.Fab" user "Ref Des/Assembly Top")
		(33 "B.Fab" user "Ref Des/Assembly Bottom")
	)
	(footprint ""
		(layer "B.Cu")
		(at 444.91275 -29.6164)
		(property "Reference" "C25W12"
			(at 0.8382 -0.67818 0)
			(unlocked yes)
			(layer "B.SilkS")
			(effects
				(font
					(size 0.4064 0.254)
					(thickness 0.1524)
				)
				(justify left mirror)
			)
		)
		(property "Value" ""
			(at 0 0 0)
			(layer "B.Fab")
			(effects
				(font
					(size 1.27 1.27)
				)
				(justify mirror)
			)
		)
		(duplicate_pad_numbers_are_jumpers no)
		(fp_poly
			(pts
				(xy -0.3048 -0.1016) (xy -0.3048 0.9906) (xy 0.3048 0.9906) (xy 0.3048 -0.1016)
			)
			(stroke
				(width 0)
				(type default)
			)
			(fill no)
			(layer "B.CrtYd")
		)
		(fp_line
			(start -0.3048 -0.1016)
			(end 0.3048 -0.1016)
			(stroke
				(width 0.1)
				(type default)
			)
			(layer "B.Fab")
		)
		(fp_line
			(start -0.3048 0.9906)
			(end -0.3048 -0.1016)
			(stroke
				(width 0.1)
				(type default)
			)
			(layer "B.Fab")
		)
		(fp_line
			(start 0.3048 -0.1016)
			(end 0.3048 0.9906)
			(stroke
				(width 0.1)
				(type default)
			)
			(layer "B.Fab")
		)
		(fp_line
			(start 0.3048 0.9906)
			(end -0.3048 0.9906)
			(stroke
				(width 0.1)
				(type default)
			)
			(layer "B.Fab")
		)
		(pad "1" smd rect
			(at 0 0 180)
			(size 0.508 0.508)
			(layers "B.Cu" "B.Mask" "B.Paste")
			(net "BMC_M_VREFCA")
		)
		(pad "2" smd rect
			(at 0 0.889 180)
			(size 0.508 0.508)
			(layers "B.Cu" "B.Mask" "B.Paste")
			(net "GND")
		)
		(zone
			(layer "B.Cu")
			(hatch none 0.5)
			(connect_pads
				(clearance 0)
			)
			(min_thickness 0.25)
			(keepout
				(tracks allowed)
				(vias not_allowed)
				(pads allowed)
				(copperpour not_allowed)
				(footprints allowed)
			)
			(placement
				(enabled no)
				(sheetname "")
			)
			(fill
				(thermal_gap 0.5)
				(thermal_bridge_width 0.5)
				(island_removal_mode 0)
			)
			(polygon
				(pts
					(xy 445.16675 -29.3624) (xy 444.65875 -29.3624) (xy 444.65875 -28.9814) (xy 445.16675 -28.9814)
				)
			)
		)
		(zone
			(layer "B.Cu")
			(hatch none 0.5)
			(connect_pads
				(clearance 0)
			)
			(min_thickness 0.25)
			(keepout
				(tracks not_allowed)
				(vias allowed)
				(pads allowed)
				(copperpour not_allowed)
				(footprints allowed)
			)
			(placement
				(enabled no)
				(sheetname "")
			)
			(fill
				(thermal_gap 0.5)
				(thermal_bridge_width 0.5)
				(island_removal_mode 0)
			)
			(polygon
				(pts
					(xy 445.16675 -28.9814) (xy 444.65875 -28.9814) (xy 444.65875 -29.3624) (xy 445.16675 -29.3624)
				)
			)
		)
	)
	(footprint ""
		(layer "B.Cu")
		(at 447.14668 -64.752982 180)
		(property "Reference" "C2P11"
			(at 0 0 0)
			(layer "B.SilkS")
			(hide yes)
			(effects
				(font
					(size 1.27 1.27)
				)
				(justify mirror)
			)
		)
		(property "Value" ""
			(at 0 0 0)
			(layer "B.Fab")
			(effects
				(font
					(size 1.27 1.27)
				)
				(justify mirror)
			)
		)
		(duplicate_pad_numbers_are_jumpers no)
		(fp_poly
			(pts
				(xy -0.3048 -0.1016) (xy -0.3048 0.9906) (xy 0.3048 0.9906) (xy 0.3048 -0.1016)
			)
			(stroke
				(width 0)
				(type default)
			)
			(fill no)
			(layer "B.CrtYd")
		)
		(fp_line
			(start 0.3048 0.9906)
			(end -0.3048 0.9906)
			(stroke
				(width 0.1)
				(type default)
			)
			(layer "B.Fab")
		)
		(fp_line
			(start 0.3048 -0.1016)
			(end 0.3048 0.9906)
			(stroke
				(width 0.1)
				(type default)
			)
			(layer "B.Fab")
		)
		(fp_line
			(start -0.3048 0.9906)
			(end -0.3048 -0.1016)
			(stroke
				(width 0.1)
				(type default)
			)
			(layer "B.Fab")
		)
		(fp_line
			(start -0.3048 -0.1016)
			(end 0.3048 -0.1016)
			(stroke
				(width 0.1)
				(type default)
			)
			(layer "B.Fab")
		)
		(pad "1" smd rect
			(at 0 0)
			(size 0.508 0.508)
			(layers "B.Cu" "B.Mask" "B.Paste")
			(net "P12V_STBY")
		)
		(pad "2" smd rect
			(at 0 0.889)
			(size 0.508 0.508)
			(layers "B.Cu" "B.Mask" "B.Paste")
			(net "GND")
		)
		(zone
			(layer "B.Cu")
			(hatch none 0.5)
			(connect_pads
				(clearance 0)
			)
			(min_thickness 0.25)
			(keepout
				(tracks not_allowed)
				(vias allowed)
				(pads allowed)
				(copperpour not_allowed)
				(footprints allowed)
			)
			(placement
				(enabled no)
				(sheetname "")
			)
			(fill
				(thermal_gap 0.5)
				(thermal_bridge_width 0.5)
				(island_removal_mode 0)
			)
			(polygon
				(pts
					(xy 446.89268 -65.387982) (xy 447.40068 -65.387982) (xy 447.40068 -65.006982) (xy 446.89268 -65.006982)
				)
			)
		)
		(zone
			(layer "B.Cu")
			(hatch none 0.5)
			(connect_pads
				(clearance 0)
			)
			(min_thickness 0.25)
			(keepout
				(tracks allowed)
				(vias not_allowed)
				(pads allowed)
				(copperpour not_allowed)
				(footprints allowed)
			)
			(placement
				(enabled no)
				(sheetname "")
			)
			(fill
				(thermal_gap 0.5)
				(thermal_bridge_width 0.5)
				(island_removal_mode 0)
			)
			(polygon
				(pts
					(xy 446.89268 -65.006982) (xy 447.40068 -65.006982) (xy 447.40068 -65.387982) (xy 446.89268 -65.387982)
				)
			)
		)
	)
	(footprint ""
		(layer "B.Cu")
		(at 328.041 -55.626 -90)
		(property "Reference" "R4R6"
			(at 0 0 90)
			(layer "B.SilkS")
			(hide yes)
			(effects
				(font
					(size 1.27 1.27)
				)
				(justify mirror)
			)
		)
		(property "Value" ""
			(at 0 0 90)
			(layer "B.Fab")
			(effects
				(font
					(size 1.27 1.27)
				)
				(justify mirror)
			)
		)
		(duplicate_pad_numbers_are_jumpers no)
		(fp_poly
			(pts
				(xy 0.2794 -0.1016) (xy -0.2794 -0.1016) (xy -0.2794 0.9906) (xy 0.2794 0.9906)
			)
			(stroke
				(width 0)
				(type default)
			)
			(fill no)
			(layer "B.CrtYd")
		)
		(fp_line
			(start -0.2794 0.9906)
			(end -0.2794 -0.1016)
			(stroke
				(width 0.1)
				(type default)
			)
			(layer "B.Fab")
		)
		(fp_line
			(start 0.2794 0.9906)
			(end -0.2794 0.9906)
			(stroke
				(width 0.1)
				(type default)
			)
			(layer "B.Fab")
		)
		(fp_line
			(start -0.2794 -0.1016)
			(end 0.2794 -0.1016)
			(stroke
				(width 0.1)
				(type default)
			)
			(layer "B.Fab")
		)
		(fp_line
			(start 0.2794 -0.1016)
			(end 0.2794 0.9906)
			(stroke
				(width 0.1)
				(type default)
			)
			(layer "B.Fab")
		)
		(pad "1" smd rect
			(at 0 0 90)
			(size 0.508 0.508)
			(layers "B.Cu" "B.Mask" "B.Paste")
			(net "JTAG_MCP_CPU0_TDI_R")
		)
		(pad "2" smd rect
			(at 0 0.889 90)
			(size 0.508 0.508)
			(layers "B.Cu" "B.Mask" "B.Paste")
			(net "JTAG_MCP_CPU0_TDI")
		)
		(zone
			(layer "B.Cu")
			(hatch none 0.5)
			(connect_pads
				(clearance 0)
			)
			(min_thickness 0.25)
			(keepout
				(tracks not_allowed)
				(vias allowed)
				(pads allowed)
				(copperpour not_allowed)
				(footprints allowed)
			)
			(placement
				(enabled no)
				(sheetname "")
			)
			(fill
				(thermal_gap 0.5)
				(thermal_bridge_width 0.5)
				(island_removal_mode 0)
			)
			(polygon
				(pts
					(xy 327.406 -55.372) (xy 327.406 -55.88) (xy 327.787 -55.88) (xy 327.787 -55.372)
				)
			)
		)
		(zone
			(layer "B.Cu")
			(hatch none 0.5)
			(connect_pads
				(clearance 0)
			)
			(min_thickness 0.25)
			(keepout
				(tracks allowed)
				(vias not_allowed)
				(pads allowed)
				(copperpour not_allowed)
				(footprints allowed)
			)
			(placement
				(enabled no)
				(sheetname "")
			)
			(fill
				(thermal_gap 0.5)
				(thermal_bridge_width 0.5)
				(island_removal_mode 0)
			)
			(polygon
				(pts
					(xy 327.787 -55.372) (xy 327.787 -55.88) (xy 327.406 -55.88) (xy 327.406 -55.372)
				)
			)
		)
	)
	(footprint ""
		(layer "B.Cu")
		(at 454.787 -142.0114)
		(property "Reference" "C9A6"
			(at 0 0 0)
			(layer "B.SilkS")
			(hide yes)
			(effects
				(font
					(size 1.27 1.27)
				)
				(justify mirror)
			)
		)
		(property "Value" ""
			(at 0 0 0)
			(layer "B.Fab")
			(effects
				(font
					(size 1.27 1.27)
				)
				(justify mirror)
			)
		)
		(duplicate_pad_numbers_are_jumpers no)
		(fp_poly
			(pts
				(xy -0.3048 -0.1016) (xy -0.3048 0.9906) (xy 0.3048 0.9906) (xy 0.3048 -0.1016)
			)
			(stroke
				(width 0)
				(type default)
			)
			(fill no)
			(layer "B.CrtYd")
		)
		(fp_line
			(start -0.3048 -0.1016)
			(end 0.3048 -0.1016)
			(stroke
				(width 0.1)
				(type default)
			)
			(layer "B.Fab")
		)
		(fp_line
			(start -0.3048 0.9906)
			(end -0.3048 -0.1016)
			(stroke
				(width 0.1)
				(type default)
			)
			(layer "B.Fab")
		)
		(fp_line
			(start 0.3048 -0.1016)
			(end 0.3048 0.9906)
			(stroke
				(width 0.1)
				(type default)
			)
			(layer "B.Fab")
		)
		(fp_line
			(start 0.3048 0.9906)
			(end -0.3048 0.9906)
			(stroke
				(width 0.1)
				(type default)
			)
			(layer "B.Fab")
		)
		(pad "1" smd rect
			(at 0 0 180)
			(size 0.508 0.508)
			(layers "B.Cu" "B.Mask" "B.Paste")
			(net "P1V05_PCH_STBY")
		)
		(pad "2" smd rect
			(at 0 0.889 180)
			(size 0.508 0.508)
			(layers "B.Cu" "B.Mask" "B.Paste")
			(net "GND")
		)
		(zone
			(layer "B.Cu")
			(hatch none 0.5)
			(connect_pads
				(clearance 0)
			)
			(min_thickness 0.25)
			(keepout
				(tracks allowed)
				(vias not_allowed)
				(pads allowed)
				(copperpour not_allowed)
				(footprints allowed)
			)
			(placement
				(enabled no)
				(sheetname "")
			)
			(fill
				(thermal_gap 0.5)
				(thermal_bridge_width 0.5)
				(island_removal_mode 0)
			)
			(polygon
				(pts
					(xy 455.041 -141.7574) (xy 454.533 -141.7574) (xy 454.533 -141.3764) (xy 455.041 -141.3764)
				)
			)
		)
		(zone
			(layer "B.Cu")
			(hatch none 0.5)
			(connect_pads
				(clearance 0)
			)
			(min_thickness 0.25)
			(keepout
				(tracks not_allowed)
				(vias allowed)
				(pads allowed)
				(copperpour not_allowed)
				(footprints allowed)
			)
			(placement
				(enabled no)
				(sheetname "")
			)
			(fill
				(thermal_gap 0.5)
				(thermal_bridge_width 0.5)
				(island_removal_mode 0)
			)
			(polygon
				(pts
					(xy 455.041 -141.3764) (xy 454.533 -141.3764) (xy 454.533 -141.7574) (xy 455.041 -141.7574)
				)
			)
		)
	)
	(footprint ""
		(layer "B.Cu")
		(at 479.11766 -27.70632 180)
		(property "Reference" "C2T18"
			(at 0 0 0)
			(layer "B.SilkS")
			(hide yes)
			(effects
				(font
					(size 1.27 1.27)
				)
				(justify mirror)
			)
		)
		(property "Value" ""
			(at 0 0 0)
			(layer "B.Fab")
			(effects
				(font
					(size 1.27 1.27)
				)
				(justify mirror)
			)
		)
		(duplicate_pad_numbers_are_jumpers no)
		(fp_poly
			(pts
				(xy -0.3048 -0.1016) (xy -0.3048 0.9906) (xy 0.3048 0.9906) (xy 0.3048 -0.1016)
			)
			(stroke
				(width 0)
				(type default)
			)
			(fill no)
			(layer "B.CrtYd")
		)
		(fp_line
			(start 0.3048 0.9906)
			(end -0.3048 0.9906)
			(stroke
				(width 0.1)
				(type default)
			)
			(layer "B.Fab")
		)
		(fp_line
			(start 0.3048 -0.1016)
			(end 0.3048 0.9906)
			(stroke
				(width 0.1)
				(type default)
			)
			(layer "B.Fab")
		)
		(fp_line
			(start -0.3048 0.9906)
			(end -0.3048 -0.1016)
			(stroke
				(width 0.1)
				(type default)
			)
			(layer "B.Fab")
		)
		(fp_line
			(start -0.3048 -0.1016)
			(end 0.3048 -0.1016)
			(stroke
				(width 0.1)
				(type default)
			)
			(layer "B.Fab")
		)
		(pad "1" smd rect
			(at 0 0)
			(size 0.508 0.508)
			(layers "B.Cu" "B.Mask" "B.Paste")
			(net "P3V3_STBY_MNG_CPU")
		)
		(pad "2" smd rect
			(at 0 0.889)
			(size 0.508 0.508)
			(layers "B.Cu" "B.Mask" "B.Paste")
			(net "GND")
		)
		(zone
			(layer "B.Cu")
			(hatch none 0.5)
			(connect_pads
				(clearance 0)
			)
			(min_thickness 0.25)
			(keepout
				(tracks not_allowed)
				(vias allowed)
				(pads allowed)
				(copperpour not_allowed)
				(footprints allowed)
			)
			(placement
				(enabled no)
				(sheetname "")
			)
			(fill
				(thermal_gap 0.5)
				(thermal_bridge_width 0.5)
				(island_removal_mode 0)
			)
			(polygon
				(pts
					(xy 478.86366 -28.34132) (xy 479.37166 -28.34132) (xy 479.37166 -27.96032) (xy 478.86366 -27.96032)
				)
			)
		)
		(zone
			(layer "B.Cu")
			(hatch none 0.5)
			(connect_pads
				(clearance 0)
			)
			(min_thickness 0.25)
			(keepout
				(tracks allowed)
				(vias not_allowed)
				(pads allowed)
				(copperpour not_allowed)
				(footprints allowed)
			)
			(placement
				(enabled no)
				(sheetname "")
			)
			(fill
				(thermal_gap 0.5)
				(thermal_bridge_width 0.5)
				(island_removal_mode 0)
			)
			(polygon
				(pts
					(xy 478.86366 -27.96032) (xy 479.37166 -27.96032) (xy 479.37166 -28.34132) (xy 478.86366 -28.34132)
				)
			)
		)
	)
	(footprint ""
		(layer "B.Cu")
		(at 448.544188 -37.032692 90)
		(property "Reference" "R25W38"
			(at 0 0 90)
			(layer "B.SilkS")
			(hide yes)
			(effects
				(font
					(size 1.27 1.27)
				)
				(justify mirror)
			)
		)
		(property "Value" "*"
			(at -0.064008 -4.108196 90)
			(unlocked yes)
			(layer "B.Fab")
			(hide yes)
			(effects
				(font
					(size 1.27 1.016)
					(thickness 0.1524)
				)
				(justify mirror)
			)
		)
		(property "Device Type" "120R2F-GP_RCL_GP-120R2F-GP,64.A"
			(at -0.064008 -5.632196 90)
			(unlocked yes)
			(layer "B.Fab")
			(hide yes)
			(effects
				(font
					(size 1.27 1.016)
					(thickness 0.1524)
				)
				(justify mirror)
			)
		)
		(duplicate_pad_numbers_are_jumpers no)
		(fp_line
			(start 0.508 -0.9398)
			(end 0.508 0.9398)
			(stroke
				(width 0.1524)
				(type default)
			)
			(layer "B.SilkS")
		)
		(fp_line
			(start -0.508 -0.9398)
			(end 0.508 -0.9398)
			(stroke
				(width 0.1524)
				(type default)
			)
			(layer "B.SilkS")
		)
		(fp_rect
			(start 0.508 0.9398)
			(end -0.508 -0.9398)
			(stroke
				(width 0)
				(type default)
			)
			(fill no)
			(layer "B.CrtYd")
		)
		(fp_rect
			(start 0.508 0.9398)
			(end -0.508 -0.9398)
			(stroke
				(width 0)
				(type default)
			)
			(fill no)
			(layer "B.Fab")
		)
		(pad "1" smd custom
			(at 0 -0.4445 270)
			(size 0.1397 0.1397)
			(layers "B.Cu" "B.Mask" "B.Paste")
			(net "BMC_M_A0")
			(options
				(clearance outline)
				(anchor circle)
			)
			(primitives
				(gr_poly
					(pts
						(arc
							(start -0.1778 0.2794)
							(mid -0.249642 0.249642)
							(end -0.2794 0.1778)
						)
						(arc
							(start -0.2794 -0.1778)
							(mid -0.249642 -0.249642)
							(end -0.1778 -0.2794)
						)
						(arc
							(start 0.1778 -0.2794)
							(mid 0.249642 -0.249642)
							(end 0.2794 -0.1778)
						)
						(arc
							(start 0.2794 0.1778)
							(mid 0.249642 0.249642)
							(end 0.1778 0.2794)
						)
					)
					(width 0)
					(fill yes)
				)
			)
		)
		(pad "2" smd custom
			(at 0 0.4445 270)
			(size 0.1397 0.1397)
			(layers "B.Cu" "B.Mask" "B.Paste")
			(net "P1V2_AUX_BMC")
			(options
				(clearance outline)
				(anchor circle)
			)
			(primitives
				(gr_poly
					(pts
						(arc
							(start -0.1778 0.2794)
							(mid -0.249642 0.249642)
							(end -0.2794 0.1778)
						)
						(arc
							(start -0.2794 -0.1778)
							(mid -0.249642 -0.249642)
							(end -0.1778 -0.2794)
						)
						(arc
							(start 0.1778 -0.2794)
							(mid 0.249642 -0.249642)
							(end 0.2794 -0.1778)
						)
						(arc
							(start 0.2794 0.1778)
							(mid 0.249642 0.249642)
							(end 0.1778 0.2794)
						)
					)
					(width 0)
					(fill yes)
				)
			)
		)
	)
	(footprint ""
		(layer "B.Cu")
		(at 394.171932 -25.143714 180)
		(property "Reference" "C32W5"
			(at 0.8382 -0.67818 180)
			(unlocked yes)
			(layer "B.SilkS")
			(effects
				(font
					(size 0.4064 0.254)
					(thickness 0.1524)
				)
				(justify left mirror)
			)
		)
		(property "Value" ""
			(at 0 0 0)
			(layer "B.Fab")
			(effects
				(font
					(size 1.27 1.27)
				)
				(justify mirror)
			)
		)
		(duplicate_pad_numbers_are_jumpers no)
		(fp_poly
			(pts
				(xy -0.3048 -0.1016) (xy -0.3048 0.9906) (xy 0.3048 0.9906) (xy 0.3048 -0.1016)
			)
			(stroke
				(width 0)
				(type default)
			)
			(fill no)
			(layer "B.CrtYd")
		)
		(fp_line
			(start 0.3048 0.9906)
			(end -0.3048 0.9906)
			(stroke
				(width 0.1)
				(type default)
			)
			(layer "B.Fab")
		)
		(fp_line
			(start 0.3048 -0.1016)
			(end 0.3048 0.9906)
			(stroke
				(width 0.1)
				(type default)
			)
			(layer "B.Fab")
		)
		(fp_line
			(start -0.3048 0.9906)
			(end -0.3048 -0.1016)
			(stroke
				(width 0.1)
				(type default)
			)
			(layer "B.Fab")
		)
		(fp_line
			(start -0.3048 -0.1016)
			(end 0.3048 -0.1016)
			(stroke
				(width 0.1)
				(type default)
			)
			(layer "B.Fab")
		)
		(pad "1" smd rect
			(at 0 0)
			(size 0.508 0.508)
			(layers "B.Cu" "B.Mask" "B.Paste")
			(net "P1V8_M2")
		)
		(pad "2" smd rect
			(at 0 0.889)
			(size 0.508 0.508)
			(layers "B.Cu" "B.Mask" "B.Paste")
			(net "GND")
		)
		(zone
			(layer "B.Cu")
			(hatch none 0.5)
			(connect_pads
				(clearance 0)
			)
			(min_thickness 0.25)
			(keepout
				(tracks not_allowed)
				(vias allowed)
				(pads allowed)
				(copperpour not_allowed)
				(footprints allowed)
			)
			(placement
				(enabled no)
				(sheetname "")
			)
			(fill
				(thermal_gap 0.5)
				(thermal_bridge_width 0.5)
				(island_removal_mode 0)
			)
			(polygon
				(pts
					(xy 393.917932 -25.778714) (xy 394.425932 -25.778714) (xy 394.425932 -25.397714) (xy 393.917932 -25.397714)
				)
			)
		)
		(zone
			(layer "B.Cu")
			(hatch none 0.5)
			(connect_pads
				(clearance 0)
			)
			(min_thickness 0.25)
			(keepout
				(tracks allowed)
				(vias not_allowed)
				(pads allowed)
				(copperpour not_allowed)
				(footprints allowed)
			)
			(placement
				(enabled no)
				(sheetname "")
			)
			(fill
				(thermal_gap 0.5)
				(thermal_bridge_width 0.5)
				(island_removal_mode 0)
			)
			(polygon
				(pts
					(xy 393.917932 -25.397714) (xy 394.425932 -25.397714) (xy 394.425932 -25.778714) (xy 393.917932 -25.778714)
				)
			)
		)
	)
)
